(kicad_pcb
	(version 20260206)
	(generator "pcbnew")
	(generator_version "10.0")
	(general
		(thickness 1.6)
		(legacy_teardrops no)
	)
	(paper "A4")
	(title_block
		(title "Bryce Canyon_SCC_16316-1_OCP.brd")
		(comment 1 "Bryce Canyon / footprints 1057-1064 of 1561")
	)
	(layers
		(0 "F.Cu" signal "TOP")
		(4 "In1.Cu" signal "L2GND")
		(6 "In2.Cu" signal "L3")
		(8 "In3.Cu" signal "L4VCC")
		(10 "In4.Cu" signal "L5VCC")
		(12 "In5.Cu" signal "L6")
		(14 "In6.Cu" signal "L7GND")
		(2 "B.Cu" signal "BOTTOM")
		(9 "F.Adhes" user "F.Adhesive")
		(11 "B.Adhes" user "B.Adhesive")
		(13 "F.Paste" user "Package Geometry/Pastemask Top")
		(15 "B.Paste" user "Package Geometry/Pastemask Bottom")
		(5 "F.SilkS" user "Ref Des/Silkscreen Top")
		(7 "B.SilkS" user "Ref Des/Silkscreen Bottom")
		(1 "F.Mask" user "Board Geometry/Soldermask Top")
		(3 "B.Mask" user "Board Geometry/Soldermask Bottom")
		(17 "Dwgs.User" user "User.Drawings")
		(19 "Cmts.User" user "User.Comments")
		(21 "Eco1.User" user "User.Eco1")
		(23 "Eco2.User" user "User.Eco2")
		(25 "Edge.Cuts" user "Board Geometry/Outline")
		(27 "Margin" user)
		(31 "F.CrtYd" user "Package Geometry/Place Bound Top")
		(29 "B.CrtYd" user "Package Geometry/Place Bound Bottom")
		(35 "F.Fab" user "Ref Des/Assembly Top")
		(33 "B.Fab" user "Ref Des/Assembly Bottom")
	)
	(footprint ""
		(layer "B.Cu")
		(at 73.66 -46.736)
		(property "Reference" "C298"
			(at 0 0 0)
			(layer "B.SilkS")
			(hide yes)
			(effects
				(font
					(size 1.27 1.27)
				)
				(justify mirror)
			)
		)
		(property "Value" "SC100U6D3V6MX-GP"
			(at 0.0762 -5.1308 0)
			(unlocked yes)
			(layer "B.Fab")
			(hide yes)
			(effects
				(font
					(size 1.016 1.016)
					(thickness 0.1524)
				)
				(justify mirror)
			)
		)
		(property "Device Type" "C1206H71"
			(at 0.127 -6.6548 0)
			(unlocked yes)
			(layer "B.Fab")
			(hide yes)
			(effects
				(font
					(size 1.016 1.016)
					(thickness 0.1524)
				)
				(justify mirror)
			)
		)
		(duplicate_pad_numbers_are_jumpers no)
		(fp_line
			(start -1.016 -2.2352)
			(end -1.016 -0.8382)
			(stroke
				(width 0.1524)
				(type default)
			)
			(layer "B.SilkS")
		)
		(fp_line
			(start -1.016 0.8382)
			(end -1.016 2.2352)
			(stroke
				(width 0.1524)
				(type default)
			)
			(layer "B.SilkS")
		)
		(fp_line
			(start -1.016 2.2352)
			(end 1.016 2.2352)
			(stroke
				(width 0.1524)
				(type default)
			)
			(layer "B.SilkS")
		)
		(fp_line
			(start 1.016 -2.2352)
			(end -1.016 -2.2352)
			(stroke
				(width 0.1524)
				(type default)
			)
			(layer "B.SilkS")
		)
		(fp_line
			(start 1.016 -0.8382)
			(end 1.016 -2.2352)
			(stroke
				(width 0.1524)
				(type default)
			)
			(layer "B.SilkS")
		)
		(fp_line
			(start 1.016 2.2352)
			(end 1.016 0.8382)
			(stroke
				(width 0.1524)
				(type default)
			)
			(layer "B.SilkS")
		)
		(fp_rect
			(start 1.0922 2.3114)
			(end -1.0922 -2.3114)
			(stroke
				(width 0)
				(type default)
			)
			(fill no)
			(layer "B.CrtYd")
		)
		(fp_poly
			(pts
				(xy -1.0922 -2.3114) (xy -1.0922 2.3114) (xy 1.0922 2.3114) (xy 1.0922 -2.3114)
			)
			(stroke
				(width 0)
				(type default)
			)
			(fill no)
			(layer "B.Fab")
		)
		(pad "1" smd rect
			(at 0 -1.397 180)
			(size 1.651 1.27)
			(layers "B.Cu" "B.Mask" "B.Paste")
			(net "GB_VDDA")
		)
		(pad "2" smd rect
			(at 0 1.397 180)
			(size 1.651 1.27)
			(layers "B.Cu" "B.Mask" "B.Paste")
			(net "GND")
		)
	)
	(footprint ""
		(layer "B.Cu")
		(at 119.2657 -57.4802)
		(property "Reference" "C268"
			(at 0 0 0)
			(layer "B.SilkS")
			(hide yes)
			(effects
				(font
					(size 1.27 1.27)
				)
				(justify mirror)
			)
		)
		(property "Value" "SCD1U6D3V1KX-GP"
			(at 2.8321 -1.7399 0)
			(unlocked yes)
			(layer "B.Fab")
			(hide yes)
			(effects
				(font
					(size 1.016 1.016)
					(thickness 0.1524)
				)
				(justify mirror)
			)
		)
		(property "Device Type" "C0201H13"
			(at 2.8321 -3.2639 0)
			(unlocked yes)
			(layer "B.Fab")
			(hide yes)
			(effects
				(font
					(size 1.016 1.016)
					(thickness 0.1524)
				)
				(justify mirror)
			)
		)
		(duplicate_pad_numbers_are_jumpers no)
		(fp_rect
			(start 0.2794 0.6477)
			(end -0.2794 -0.6477)
			(stroke
				(width 0)
				(type default)
			)
			(fill no)
			(layer "B.CrtYd")
		)
		(fp_rect
			(start 0.2794 0.6477)
			(end -0.2794 -0.6477)
			(stroke
				(width 0)
				(type default)
			)
			(fill no)
			(layer "B.Fab")
		)
		(pad "1" smd custom
			(at 0 -0.2794 180)
			(size 0.0762 0.0762)
			(layers "B.Cu" "B.Mask" "B.Paste")
			(net "GB_VDDA")
			(options
				(clearance outline)
				(anchor circle)
			)
			(primitives
				(gr_poly
					(pts
						(arc
							(start 0.1524 0.127)
							(mid 0.137521 0.162921)
							(end 0.1016 0.1778)
						)
						(arc
							(start -0.1016 0.1778)
							(mid -0.137521 0.162921)
							(end -0.1524 0.127)
						)
						(arc
							(start -0.1524 -0.127)
							(mid -0.137521 -0.162921)
							(end -0.1016 -0.1778)
						)
						(arc
							(start 0.1016 -0.1778)
							(mid 0.137521 -0.162921)
							(end 0.1524 -0.127)
						)
					)
					(width 0)
					(fill yes)
				)
			)
		)
		(pad "2" smd custom
			(at 0 0.2794 180)
			(size 0.0762 0.0762)
			(layers "B.Cu" "B.Mask" "B.Paste")
			(net "GND")
			(options
				(clearance outline)
				(anchor circle)
			)
			(primitives
				(gr_poly
					(pts
						(arc
							(start 0.1524 0.127)
							(mid 0.137521 0.162921)
							(end 0.1016 0.1778)
						)
						(arc
							(start -0.1016 0.1778)
							(mid -0.137521 0.162921)
							(end -0.1524 0.127)
						)
						(arc
							(start -0.1524 -0.127)
							(mid -0.137521 -0.162921)
							(end -0.1016 -0.1778)
						)
						(arc
							(start 0.1016 -0.1778)
							(mid 0.137521 -0.162921)
							(end 0.1524 -0.127)
						)
					)
					(width 0)
					(fill yes)
				)
			)
		)
	)
	(footprint ""
		(layer "B.Cu")
		(at 106.500168 -75.50023)
		(property "Reference" "TP163"
			(at 0 0 0)
			(layer "B.SilkS")
			(hide yes)
			(effects
				(font
					(size 1.27 1.27)
				)
				(justify mirror)
			)
		)
		(property "Value" "TPAD28-2-GP"
			(at 0.0127 -1.6637 0)
			(unlocked yes)
			(layer "B.Fab")
			(hide yes)
			(effects
				(font
					(size 1.016 1.016)
					(thickness 0.1524)
				)
				(justify mirror)
			)
		)
		(property "Device Type" "TPAD28"
			(at 0.0127 -3.1877 0)
			(unlocked yes)
			(layer "B.Fab")
			(hide yes)
			(effects
				(font
					(size 1.016 1.016)
					(thickness 0.1524)
				)
				(justify mirror)
			)
		)
		(duplicate_pad_numbers_are_jumpers no)
		(fp_poly
			(pts
				(arc
					(start 0.3556 0)
					(mid -0.3556 0)
					(end 0.3556 0)
				)
			)
			(stroke
				(width 0)
				(type default)
			)
			(fill no)
			(layer "B.CrtYd")
		)
		(fp_poly
			(pts
				(arc
					(start 0.6096 0)
					(mid -0.6096 0)
					(end 0.6096 0)
				)
			)
			(stroke
				(width 0)
				(type default)
			)
			(fill no)
			(layer "B.Fab")
		)
		(pad "1" smd circle
			(at 0 0 180)
			(size 0.7112 0.7112)
			(layers "B.Cu" "B.Mask" "B.Paste")
			(net "LED11")
		)
	)
	(footprint ""
		(layer "B.Cu")
		(at 109.2708 -57.4802)
		(property "Reference" "C579"
			(at 0 0 0)
			(layer "B.SilkS")
			(hide yes)
			(effects
				(font
					(size 1.27 1.27)
				)
				(justify mirror)
			)
		)
		(property "Value" "SCD1U6D3V1KX-GP"
			(at 2.8321 -1.7399 0)
			(unlocked yes)
			(layer "B.Fab")
			(hide yes)
			(effects
				(font
					(size 1.016 1.016)
					(thickness 0.1524)
				)
				(justify mirror)
			)
		)
		(property "Device Type" "C0201H13"
			(at 2.8321 -3.2639 0)
			(unlocked yes)
			(layer "B.Fab")
			(hide yes)
			(effects
				(font
					(size 1.016 1.016)
					(thickness 0.1524)
				)
				(justify mirror)
			)
		)
		(duplicate_pad_numbers_are_jumpers no)
		(fp_rect
			(start 0.2794 0.6477)
			(end -0.2794 -0.6477)
			(stroke
				(width 0)
				(type default)
			)
			(fill no)
			(layer "B.CrtYd")
		)
		(fp_rect
			(start 0.2794 0.6477)
			(end -0.2794 -0.6477)
			(stroke
				(width 0)
				(type default)
			)
			(fill no)
			(layer "B.Fab")
		)
		(pad "1" smd custom
			(at 0 -0.2794 180)
			(size 0.0762 0.0762)
			(layers "B.Cu" "B.Mask" "B.Paste")
			(net "GB_VDDA")
			(options
				(clearance outline)
				(anchor circle)
			)
			(primitives
				(gr_poly
					(pts
						(arc
							(start 0.1524 0.127)
							(mid 0.137521 0.162921)
							(end 0.1016 0.1778)
						)
						(arc
							(start -0.1016 0.1778)
							(mid -0.137521 0.162921)
							(end -0.1524 0.127)
						)
						(arc
							(start -0.1524 -0.127)
							(mid -0.137521 -0.162921)
							(end -0.1016 -0.1778)
						)
						(arc
							(start 0.1016 -0.1778)
							(mid 0.137521 -0.162921)
							(end 0.1524 -0.127)
						)
					)
					(width 0)
					(fill yes)
				)
			)
		)
		(pad "2" smd custom
			(at 0 0.2794 180)
			(size 0.0762 0.0762)
			(layers "B.Cu" "B.Mask" "B.Paste")
			(net "GND")
			(options
				(clearance outline)
				(anchor circle)
			)
			(primitives
				(gr_poly
					(pts
						(arc
							(start 0.1524 0.127)
							(mid 0.137521 0.162921)
							(end 0.1016 0.1778)
						)
						(arc
							(start -0.1016 0.1778)
							(mid -0.137521 0.162921)
							(end -0.1524 0.127)
						)
						(arc
							(start -0.1524 -0.127)
							(mid -0.137521 -0.162921)
							(end -0.1016 -0.1778)
						)
						(arc
							(start 0.1016 -0.1778)
							(mid 0.137521 -0.162921)
							(end 0.1524 -0.127)
						)
					)
					(width 0)
					(fill yes)
				)
			)
		)
	)
	(footprint ""
		(layer "B.Cu")
		(at 177.60823 -28.64485 180)
		(property "Reference" "C386"
			(at 0 0 0)
			(layer "B.SilkS")
			(hide yes)
			(effects
				(font
					(size 1.27 1.27)
				)
				(justify mirror)
			)
		)
		(property "Value" "SCD1U6D3V1KX-GP"
			(at 2.8321 -1.7399 180)
			(unlocked yes)
			(layer "B.Fab")
			(hide yes)
			(effects
				(font
					(size 1.016 1.016)
					(thickness 0.1524)
				)
				(justify mirror)
			)
		)
		(property "Device Type" "C0201H13"
			(at 2.8321 -3.2639 180)
			(unlocked yes)
			(layer "B.Fab")
			(hide yes)
			(effects
				(font
					(size 1.016 1.016)
					(thickness 0.1524)
				)
				(justify mirror)
			)
		)
		(duplicate_pad_numbers_are_jumpers no)
		(fp_rect
			(start 0.2794 0.6477)
			(end -0.2794 -0.6477)
			(stroke
				(width 0)
				(type default)
			)
			(fill no)
			(layer "B.CrtYd")
		)
		(fp_rect
			(start 0.2794 0.6477)
			(end -0.2794 -0.6477)
			(stroke
				(width 0)
				(type default)
			)
			(fill no)
			(layer "B.Fab")
		)
		(pad "1" smd custom
			(at 0 -0.2794)
			(size 0.0762 0.0762)
			(layers "B.Cu" "B.Mask" "B.Paste")
			(net "PCE_AVDD")
			(options
				(clearance outline)
				(anchor circle)
			)
			(primitives
				(gr_poly
					(pts
						(arc
							(start 0.1524 0.127)
							(mid 0.137521 0.162921)
							(end 0.1016 0.1778)
						)
						(arc
							(start -0.1016 0.1778)
							(mid -0.137521 0.162921)
							(end -0.1524 0.127)
						)
						(arc
							(start -0.1524 -0.127)
							(mid -0.137521 -0.162921)
							(end -0.1016 -0.1778)
						)
						(arc
							(start 0.1016 -0.1778)
							(mid 0.137521 -0.162921)
							(end 0.1524 -0.127)
						)
					)
					(width 0)
					(fill yes)
				)
			)
		)
		(pad "2" smd custom
			(at 0 0.2794)
			(size 0.0762 0.0762)
			(layers "B.Cu" "B.Mask" "B.Paste")
			(net "GND")
			(options
				(clearance outline)
				(anchor circle)
			)
			(primitives
				(gr_poly
					(pts
						(arc
							(start 0.1524 0.127)
							(mid 0.137521 0.162921)
							(end 0.1016 0.1778)
						)
						(arc
							(start -0.1016 0.1778)
							(mid -0.137521 0.162921)
							(end -0.1524 0.127)
						)
						(arc
							(start -0.1524 -0.127)
							(mid -0.137521 -0.162921)
							(end -0.1016 -0.1778)
						)
						(arc
							(start 0.1016 -0.1778)
							(mid 0.137521 -0.162921)
							(end 0.1524 -0.127)
						)
					)
					(width 0)
					(fill yes)
				)
			)
		)
	)
	(footprint ""
		(layer "B.Cu")
		(at 110.9218 -44.2214 180)
		(property "Reference" "C69"
			(at 0 0 0)
			(layer "B.SilkS")
			(hide yes)
			(effects
				(font
					(size 1.27 1.27)
				)
				(justify mirror)
			)
		)
		(property "Value" "SCD01U16V1KX-GP"
			(at 2.8321 -1.7399 180)
			(unlocked yes)
			(layer "B.Fab")
			(hide yes)
			(effects
				(font
					(size 1.016 1.016)
					(thickness 0.1524)
				)
				(justify mirror)
			)
		)
		(property "Device Type" "C0201H13"
			(at 2.8321 -3.2639 180)
			(unlocked yes)
			(layer "B.Fab")
			(hide yes)
			(effects
				(font
					(size 1.016 1.016)
					(thickness 0.1524)
				)
				(justify mirror)
			)
		)
		(duplicate_pad_numbers_are_jumpers no)
		(fp_rect
			(start 0.2794 0.6477)
			(end -0.2794 -0.6477)
			(stroke
				(width 0)
				(type default)
			)
			(fill no)
			(layer "B.CrtYd")
		)
		(fp_rect
			(start 0.2794 0.6477)
			(end -0.2794 -0.6477)
			(stroke
				(width 0)
				(type default)
			)
			(fill no)
			(layer "B.Fab")
		)
		(pad "1" smd custom
			(at 0 -0.2794)
			(size 0.0762 0.0762)
			(layers "B.Cu" "B.Mask" "B.Paste")
			(net "PHY_DPB_TO_SCC_25_DP")
			(options
				(clearance outline)
				(anchor circle)
			)
			(primitives
				(gr_poly
					(pts
						(arc
							(start 0.1524 0.127)
							(mid 0.137521 0.162921)
							(end 0.1016 0.1778)
						)
						(arc
							(start -0.1016 0.1778)
							(mid -0.137521 0.162921)
							(end -0.1524 0.127)
						)
						(arc
							(start -0.1524 -0.127)
							(mid -0.137521 -0.162921)
							(end -0.1016 -0.1778)
						)
						(arc
							(start 0.1016 -0.1778)
							(mid 0.137521 -0.162921)
							(end 0.1524 -0.127)
						)
					)
					(width 0)
					(fill yes)
				)
			)
		)
		(pad "2" smd custom
			(at 0 0.2794)
			(size 0.0762 0.0762)
			(layers "B.Cu" "B.Mask" "B.Paste")
			(net "PHY_DPB_TO_SCC_C_25_DP")
			(options
				(clearance outline)
				(anchor circle)
			)
			(primitives
				(gr_poly
					(pts
						(arc
							(start 0.1524 0.127)
							(mid 0.137521 0.162921)
							(end 0.1016 0.1778)
						)
						(arc
							(start -0.1016 0.1778)
							(mid -0.137521 0.162921)
							(end -0.1524 0.127)
						)
						(arc
							(start -0.1524 -0.127)
							(mid -0.137521 -0.162921)
							(end -0.1016 -0.1778)
						)
						(arc
							(start 0.1016 -0.1778)
							(mid 0.137521 -0.162921)
							(end 0.1524 -0.127)
						)
					)
					(width 0)
					(fill yes)
				)
			)
		)
	)
	(footprint ""
		(layer "B.Cu")
		(at 142.0622 -123.1646 90)
		(property "Reference" "Q10"
			(at 0 0 90)
			(layer "B.SilkS")
			(hide yes)
			(effects
				(font
					(size 1.27 1.27)
				)
				(justify mirror)
			)
		)
		(property "Value" "2N7002K-1-GP"
			(at -0.127 -8.9662 90)
			(unlocked yes)
			(layer "B.Fab")
			(hide yes)
			(effects
				(font
					(size 1.016 1.016)
					(thickness 0.1524)
				)
				(justify mirror)
			)
		)
		(property "Device Type" "SOT23DGS2D4H44"
			(at -0.127 -10.4902 90)
			(unlocked yes)
			(layer "B.Fab")
			(hide yes)
			(effects
				(font
					(size 1.016 1.016)
					(thickness 0.1524)
				)
				(justify mirror)
			)
		)
		(duplicate_pad_numbers_are_jumpers no)
		(fp_line
			(start 1.651 -1.778)
			(end 1.651 1.778)
			(stroke
				(width 0.1524)
				(type default)
			)
			(layer "B.SilkS")
		)
		(fp_line
			(start -1.651 -1.778)
			(end 1.651 -1.778)
			(stroke
				(width 0.1524)
				(type default)
			)
			(layer "B.SilkS")
		)
		(fp_line
			(start 1.651 1.778)
			(end -1.651 1.778)
			(stroke
				(width 0.1524)
				(type default)
			)
			(layer "B.SilkS")
		)
		(fp_line
			(start -1.651 1.778)
			(end -1.651 -1.778)
			(stroke
				(width 0.1524)
				(type default)
			)
			(layer "B.SilkS")
		)
		(fp_poly
			(pts
				(xy 1.778 1.8796) (xy 1.778 -1.8796) (xy -1.778 -1.8796) (xy -1.778 1.8796)
			)
			(stroke
				(width 0)
				(type default)
			)
			(fill no)
			(layer "B.CrtYd")
		)
		(fp_poly
			(pts
				(xy 1.778 1.8796) (xy 1.778 -1.8796) (xy -1.778 -1.8796) (xy -1.778 1.8796)
			)
			(stroke
				(width 0)
				(type default)
			)
			(fill no)
			(layer "B.Fab")
		)
		(pad "D" smd custom
			(at 0 -0.9525 270)
			(size 0.1905 0.1905)
			(layers "B.Cu" "B.Mask" "B.Paste")
			(net "P1V5_C_PG_R_1")
			(options
				(clearance outline)
				(anchor circle)
			)
			(primitives
				(gr_poly
					(pts
						(arc
							(start -0.1778 -0.5715)
							(mid -0.321484 -0.511984)
							(end -0.381 -0.3683)
						)
						(arc
							(start -0.381 0.3683)
							(mid -0.321484 0.511984)
							(end -0.1778 0.5715)
						)
						(arc
							(start 0.1778 0.5715)
							(mid 0.321484 0.511984)
							(end 0.381 0.3683)
						)
						(arc
							(start 0.381 -0.3683)
							(mid 0.321484 -0.511984)
							(end 0.1778 -0.5715)
						)
					)
					(width 0)
					(fill yes)
				)
			)
		)
		(pad "G" smd custom
			(at 0.98425 0.9525 270)
			(size 0.1905 0.1905)
			(layers "B.Cu" "B.Mask" "B.Paste")
			(net "P12V_STBY_Q10_G")
			(options
				(clearance outline)
				(anchor circle)
			)
			(primitives
				(gr_poly
					(pts
						(arc
							(start -0.1778 -0.5715)
							(mid -0.321484 -0.511984)
							(end -0.381 -0.3683)
						)
						(arc
							(start -0.381 0.3683)
							(mid -0.321484 0.511984)
							(end -0.1778 0.5715)
						)
						(arc
							(start 0.1778 0.5715)
							(mid 0.321484 0.511984)
							(end 0.381 0.3683)
						)
						(arc
							(start 0.381 -0.3683)
							(mid 0.321484 -0.511984)
							(end 0.1778 -0.5715)
						)
					)
					(width 0)
					(fill yes)
				)
			)
		)
		(pad "S" smd custom
			(at -0.98425 0.9525 270)
			(size 0.1905 0.1905)
			(layers "B.Cu" "B.Mask" "B.Paste")
			(net "GND")
			(options
				(clearance outline)
				(anchor circle)
			)
			(primitives
				(gr_poly
					(pts
						(arc
							(start -0.1778 -0.5715)
							(mid -0.321484 -0.511984)
							(end -0.381 -0.3683)
						)
						(arc
							(start -0.381 0.3683)
							(mid -0.321484 0.511984)
							(end -0.1778 0.5715)
						)
						(arc
							(start 0.1778 0.5715)
							(mid 0.321484 0.511984)
							(end 0.381 0.3683)
						)
						(arc
							(start 0.381 -0.3683)
							(mid 0.321484 -0.511984)
							(end 0.1778 -0.5715)
						)
					)
					(width 0)
					(fill yes)
				)
			)
		)
	)
	(footprint ""
		(layer "B.Cu")
		(at 122.0216 -39.4716 180)
		(property "Reference" "C55"
			(at 0 0 0)
			(layer "B.SilkS")
			(hide yes)
			(effects
				(font
					(size 1.27 1.27)
				)
				(justify mirror)
			)
		)
		(property "Value" "SCD01U16V1KX-GP"
			(at 2.8321 -1.7399 180)
			(unlocked yes)
			(layer "B.Fab")
			(hide yes)
			(effects
				(font
					(size 1.016 1.016)
					(thickness 0.1524)
				)
				(justify mirror)
			)
		)
		(property "Device Type" "C0201H13"
			(at 2.8321 -3.2639 180)
			(unlocked yes)
			(layer "B.Fab")
			(hide yes)
			(effects
				(font
					(size 1.016 1.016)
					(thickness 0.1524)
				)
				(justify mirror)
			)
		)
		(duplicate_pad_numbers_are_jumpers no)
		(fp_rect
			(start 0.2794 0.6477)
			(end -0.2794 -0.6477)
			(stroke
				(width 0)
				(type default)
			)
			(fill no)
			(layer "B.CrtYd")
		)
		(fp_rect
			(start 0.2794 0.6477)
			(end -0.2794 -0.6477)
			(stroke
				(width 0)
				(type default)
			)
			(fill no)
			(layer "B.Fab")
		)
		(pad "1" smd custom
			(at 0 -0.2794)
			(size 0.0762 0.0762)
			(layers "B.Cu" "B.Mask" "B.Paste")
			(net "PHY_DPB_TO_SCC_36_DP")
			(options
				(clearance outline)
				(anchor circle)
			)
			(primitives
				(gr_poly
					(pts
						(arc
							(start 0.1524 0.127)
							(mid 0.137521 0.162921)
							(end 0.1016 0.1778)
						)
						(arc
							(start -0.1016 0.1778)
							(mid -0.137521 0.162921)
							(end -0.1524 0.127)
						)
						(arc
							(start -0.1524 -0.127)
							(mid -0.137521 -0.162921)
							(end -0.1016 -0.1778)
						)
						(arc
							(start 0.1016 -0.1778)
							(mid 0.137521 -0.162921)
							(end 0.1524 -0.127)
						)
					)
					(width 0)
					(fill yes)
				)
			)
		)
		(pad "2" smd custom
			(at 0 0.2794)
			(size 0.0762 0.0762)
			(layers "B.Cu" "B.Mask" "B.Paste")
			(net "PHY_DPB_TO_SCC_C_36_DP")
			(options
				(clearance outline)
				(anchor circle)
			)
			(primitives
				(gr_poly
					(pts
						(arc
							(start 0.1524 0.127)
							(mid 0.137521 0.162921)
							(end 0.1016 0.1778)
						)
						(arc
							(start -0.1016 0.1778)
							(mid -0.137521 0.162921)
							(end -0.1524 0.127)
						)
						(arc
							(start -0.1524 -0.127)
							(mid -0.137521 -0.162921)
							(end -0.1016 -0.1778)
						)
						(arc
							(start 0.1016 -0.1778)
							(mid 0.137521 -0.162921)
							(end 0.1524 -0.127)
						)
					)
					(width 0)
					(fill yes)
				)
			)
		)
	)
)
